(kicad_pcb
	(version 20260206)
	(generator "pcbnew")
	(generator_version "10.0")
	(general
		(thickness 1.6)
		(legacy_teardrops no)
	)
	(paper "A4")
	(title_block
		(title "netronome-mezz — pcbd0082-001_rev01_jul9_a.brd")
		(comment 1 "Open CloudServer (Microsoft) / footprints 608-609 of 714")
	)
	(layers
		(0 "F.Cu" signal "TOP")
		(4 "In1.Cu" signal "02_GND")
		(6 "In2.Cu" signal "03_SIG")
		(8 "In3.Cu" signal "04_SIG")
		(10 "In4.Cu" signal "05_GND")
		(12 "In5.Cu" signal "06_PWR1")
		(14 "In6.Cu" signal "07_SIG")
		(16 "In7.Cu" signal "08_SIG")
		(18 "In8.Cu" signal "09_GND")
		(2 "B.Cu" signal "BOTTOM")
		(9 "F.Adhes" user "F.Adhesive")
		(11 "B.Adhes" user "B.Adhesive")
		(13 "F.Paste" user "Package Geometry/Pastemask Top")
		(15 "B.Paste" user "Package Geometry/Pastemask Bottom")
		(5 "F.SilkS" user "Ref Des/Silkscreen Top")
		(7 "B.SilkS" user "Ref Des/Silkscreen Bottom")
		(1 "F.Mask" user "Board Geometry/Soldermask Top")
		(3 "B.Mask" user "Board Geometry/Soldermask Bottom")
		(17 "Dwgs.User" user "User.Drawings")
		(19 "Cmts.User" user "User.Comments")
		(21 "Eco1.User" user "User.Eco1")
		(23 "Eco2.User" user "User.Eco2")
		(25 "Edge.Cuts" user "Board Geometry/Outline")
		(27 "Margin" user)
		(31 "F.CrtYd" user "Package Geometry/Place Bound Top")
		(29 "B.CrtYd" user "Package Geometry/Place Bound Bottom")
		(35 "F.Fab" user "Ref Des/Assembly Top")
		(33 "B.Fab" user "Ref Des/Assembly Bottom")
		(45 "User.4" user "COMPVAL_TYPE_BOTTOM")
	)
	(footprint ""
		(layer "B.Cu")
		(at 77.851 4.699 90)
		(property "Reference" "U17"
			(at 5.3975 6.35 0)
			(unlocked yes)
			(layer "B.SilkS")
			(effects
				(font
					(size 1.27 0.9652)
					(thickness 0.1524)
				)
				(justify left mirror)
			)
		)
		(property "Value" ""
			(at 0 0 90)
			(layer "B.Fab")
			(effects
				(font
					(size 1.27 1.27)
				)
				(justify mirror)
			)
		)
		(property "Component Value" "VALUE"
			(at 0.399999 -9.402597 90)
			(unlocked yes)
			(layer "User.4")
			(effects
				(font
					(size 0.254 0.254)
					(thickness 0.000001)
				)
				(justify mirror)
			)
		)
		(property "Device Type" "MEMC0051"
			(at 5.909996 -11.648211 90)
			(unlocked yes)
			(layer "B.Fab")
			(hide yes)
			(effects
				(font
					(size 1.27 0.9652)
					(thickness 0.000001)
				)
				(justify left mirror)
			)
		)
		(duplicate_pad_numbers_are_jumpers no)
		(fp_line
			(start 4.499991 -7.000011)
			(end 4.499991 7.000011)
			(stroke
				(width 0.1524)
				(type default)
			)
			(layer "B.SilkS")
		)
		(fp_line
			(start -4.499991 -7.000011)
			(end 4.499991 -7.000011)
			(stroke
				(width 0.1524)
				(type default)
			)
			(layer "B.SilkS")
		)
		(fp_line
			(start 4.499991 -5.999988)
			(end 3.499993 -7.000011)
			(stroke
				(width 0.1524)
				(type default)
			)
			(layer "B.SilkS")
		)
		(fp_line
			(start 4.499991 7.000011)
			(end -4.499991 7.000011)
			(stroke
				(width 0.1524)
				(type default)
			)
			(layer "B.SilkS")
		)
		(fp_line
			(start -4.499991 7.000011)
			(end -4.499991 -7.000011)
			(stroke
				(width 0.1524)
				(type default)
			)
			(layer "B.SilkS")
		)
		(fp_poly
			(pts
				(xy 7.50001 10.000005) (xy -7.50001 10.000005) (xy -7.50001 -10.000005) (xy 7.50001 -10.000005)
			)
			(stroke
				(width 0)
				(type default)
			)
			(fill no)
			(layer "B.CrtYd")
		)
		(fp_line
			(start 4.499991 -7.000011)
			(end 4.499991 7.000011)
			(stroke
				(width 0.1)
				(type default)
			)
			(layer "B.Fab")
		)
		(fp_line
			(start -4.499991 -7.000011)
			(end 4.499991 -7.000011)
			(stroke
				(width 0.1)
				(type default)
			)
			(layer "B.Fab")
		)
		(fp_line
			(start 4.499991 -5.999988)
			(end 3.499993 -7.000011)
			(stroke
				(width 0.1)
				(type default)
			)
			(layer "B.Fab")
		)
		(fp_line
			(start 4.499991 7.000011)
			(end -4.499991 7.000011)
			(stroke
				(width 0.1)
				(type default)
			)
			(layer "B.Fab")
		)
		(fp_line
			(start -4.499991 7.000011)
			(end -4.499991 -7.000011)
			(stroke
				(width 0.1)
				(type default)
			)
			(layer "B.Fab")
		)
		(fp_text user "1"
			(at 4.16433 -7.366 0)
			(unlocked yes)
			(layer "B.SilkS")
			(effects
				(font
					(size 0.7874 0.5842)
					(thickness 0.127)
				)
				(justify mirror)
			)
		)
		(fp_text user "A"
			(at 5.18033 -6.223 0)
			(unlocked yes)
			(layer "B.SilkS")
			(effects
				(font
					(size 0.7874 0.5842)
					(thickness 0.127)
				)
				(justify mirror)
			)
		)
		(pad "A1" smd circle
			(at 3.199994 -5.999988 270)
			(size 0.3556 0.3556)
			(layers "B.Cu" "B.Mask" "B.Paste")
			(net "DDR_VDDQ")
		)
		(pad "A2" smd circle
			(at 2.399995 -5.999988 270)
			(size 0.3556 0.3556)
			(layers "B.Cu" "B.Mask" "B.Paste")
			(net "DDR0_32A_DQ12")
		)
		(pad "A3" smd circle
			(at 1.599997 -5.999988 270)
			(size 0.3556 0.3556)
			(layers "B.Cu" "B.Mask" "B.Paste")
			(net "DDR0_32A_DQ14")
		)
		(pad "A7" smd circle
			(at -1.599997 -5.999988 270)
			(size 0.3556 0.3556)
			(layers "B.Cu" "B.Mask" "B.Paste")
			(net "DDR0_32A_DQ13")
		)
		(pad "A8" smd circle
			(at -2.399995 -5.999988 270)
			(size 0.3556 0.3556)
			(layers "B.Cu" "B.Mask" "B.Paste")
			(net "DDR_VDDQ")
		)
		(pad "A9" smd circle
			(at -3.199994 -5.999988 270)
			(size 0.3556 0.3556)
			(layers "B.Cu" "B.Mask" "B.Paste")
			(net "GND")
		)
		(pad "B1" smd circle
			(at 3.199994 -5.19999 270)
			(size 0.3556 0.3556)
			(layers "B.Cu" "B.Mask" "B.Paste")
			(net "GND")
		)
		(pad "B2" smd circle
			(at 2.399995 -5.19999 270)
			(size 0.3556 0.3556)
			(layers "B.Cu" "B.Mask" "B.Paste")
			(net "DDR_VDDQ")
		)
		(pad "B3" smd circle
			(at 1.599997 -5.19999 270)
			(size 0.3556 0.3556)
			(layers "B.Cu" "B.Mask" "B.Paste")
			(net "GND")
		)
		(pad "B7" smd circle
			(at -1.599997 -5.19999 270)
			(size 0.3556 0.3556)
			(layers "B.Cu" "B.Mask" "B.Paste")
			(net "DDR0_32A_DQS1_N")
		)
		(pad "B8" smd circle
			(at -2.399995 -5.19999 270)
			(size 0.3556 0.3556)
			(layers "B.Cu" "B.Mask" "B.Paste")
			(net "DDR0_32A_DQ11")
		)
		(pad "B9" smd circle
			(at -3.199994 -5.19999 270)
			(size 0.3556 0.3556)
			(layers "B.Cu" "B.Mask" "B.Paste")
			(net "GND")
		)
		(pad "C1" smd circle
			(at 3.199994 -4.399991 270)
			(size 0.3556 0.3556)
			(layers "B.Cu" "B.Mask" "B.Paste")
			(net "DDR_VDDQ")
		)
		(pad "C2" smd circle
			(at 2.399995 -4.399991 270)
			(size 0.3556 0.3556)
			(layers "B.Cu" "B.Mask" "B.Paste")
			(net "DDR0_32A_DQ15")
		)
		(pad "C3" smd circle
			(at 1.599997 -4.399991 270)
			(size 0.3556 0.3556)
			(layers "B.Cu" "B.Mask" "B.Paste")
			(net "DDR0_32A_DQ9")
		)
		(pad "C7" smd circle
			(at -1.599997 -4.399991 270)
			(size 0.3556 0.3556)
			(layers "B.Cu" "B.Mask" "B.Paste")
			(net "DDR0_32A_DQS1_P")
		)
		(pad "C8" smd circle
			(at -2.399995 -4.399991 270)
			(size 0.3556 0.3556)
			(layers "B.Cu" "B.Mask" "B.Paste")
			(net "DDR0_32A_DQ10")
		)
		(pad "C9" smd circle
			(at -3.199994 -4.399991 270)
			(size 0.3556 0.3556)
			(layers "B.Cu" "B.Mask" "B.Paste")
			(net "DDR_VDDQ")
		)
		(pad "D1" smd circle
			(at 3.199994 -3.599993 270)
			(size 0.3556 0.3556)
			(layers "B.Cu" "B.Mask" "B.Paste")
			(net "GND")
		)
		(pad "D2" smd circle
			(at 2.399995 -3.599993 270)
			(size 0.3556 0.3556)
			(layers "B.Cu" "B.Mask" "B.Paste")
			(net "DDR_VDDQ")
		)
		(pad "D3" smd circle
			(at 1.599997 -3.599993 270)
			(size 0.3556 0.3556)
			(layers "B.Cu" "B.Mask" "B.Paste")
			(net "DDR0_32A_DM1")
		)
		(pad "D7" smd circle
			(at -1.599997 -3.599993 270)
			(size 0.3556 0.3556)
			(layers "B.Cu" "B.Mask" "B.Paste")
			(net "DDR0_32A_DQ8")
		)
		(pad "D8" smd circle
			(at -2.399995 -3.599993 270)
			(size 0.3556 0.3556)
			(layers "B.Cu" "B.Mask" "B.Paste")
			(net "GND")
		)
		(pad "D9" smd circle
			(at -3.199994 -3.599993 270)
			(size 0.3556 0.3556)
			(layers "B.Cu" "B.Mask" "B.Paste")
			(net "DDR_VDDQ")
		)
		(pad "E1" smd circle
			(at 3.199994 -2.799994 270)
			(size 0.3556 0.3556)
			(layers "B.Cu" "B.Mask" "B.Paste")
			(net "GND")
		)
		(pad "E2" smd circle
			(at 2.399995 -2.799994 270)
			(size 0.3556 0.3556)
			(layers "B.Cu" "B.Mask" "B.Paste")
			(net "GND")
		)
		(pad "E3" smd circle
			(at 1.599997 -2.799994 270)
			(size 0.3556 0.3556)
			(layers "B.Cu" "B.Mask" "B.Paste")
			(net "DDR0_32A_DQ5")
		)
		(pad "E7" smd circle
			(at -1.599997 -2.799994 270)
			(size 0.3556 0.3556)
			(layers "B.Cu" "B.Mask" "B.Paste")
			(net "DDR0_32A_DM0")
		)
		(pad "E8" smd circle
			(at -2.399995 -2.799994 270)
			(size 0.3556 0.3556)
			(layers "B.Cu" "B.Mask" "B.Paste")
			(net "GND")
		)
		(pad "E9" smd circle
			(at -3.199994 -2.799994 270)
			(size 0.3556 0.3556)
			(layers "B.Cu" "B.Mask" "B.Paste")
			(net "DDR_VDDQ")
		)
		(pad "F1" smd circle
			(at 3.199994 -1.999996 270)
			(size 0.3556 0.3556)
			(layers "B.Cu" "B.Mask" "B.Paste")
			(net "DDR_VDDQ")
		)
		(pad "F2" smd circle
			(at 2.399995 -1.999996 270)
			(size 0.3556 0.3556)
			(layers "B.Cu" "B.Mask" "B.Paste")
			(net "DDR0_32A_DQ0")
		)
		(pad "F3" smd circle
			(at 1.599997 -1.999996 270)
			(size 0.3556 0.3556)
			(layers "B.Cu" "B.Mask" "B.Paste")
			(net "DDR0_32A_DQS0_P")
		)
		(pad "F7" smd circle
			(at -1.599997 -1.999996 270)
			(size 0.3556 0.3556)
			(layers "B.Cu" "B.Mask" "B.Paste")
			(net "DDR0_32A_DQ6")
		)
		(pad "F8" smd circle
			(at -2.399995 -1.999996 270)
			(size 0.3556 0.3556)
			(layers "B.Cu" "B.Mask" "B.Paste")
			(net "DDR0_32A_DQ7")
		)
		(pad "F9" smd circle
			(at -3.199994 -1.999996 270)
			(size 0.3556 0.3556)
			(layers "B.Cu" "B.Mask" "B.Paste")
			(net "GND")
		)
		(pad "G1" smd circle
			(at 3.199994 -1.199998 270)
			(size 0.3556 0.3556)
			(layers "B.Cu" "B.Mask" "B.Paste")
			(net "GND")
		)
		(pad "G2" smd circle
			(at 2.399995 -1.199998 270)
			(size 0.3556 0.3556)
			(layers "B.Cu" "B.Mask" "B.Paste")
			(net "DDR0_32A_DQ1")
		)
		(pad "G3" smd circle
			(at 1.599997 -1.199998 270)
			(size 0.3556 0.3556)
			(layers "B.Cu" "B.Mask" "B.Paste")
			(net "DDR0_32A_DQS0_N")
		)
		(pad "G7" smd circle
			(at -1.599997 -1.199998 270)
			(size 0.3556 0.3556)
			(layers "B.Cu" "B.Mask" "B.Paste")
			(net "DDR_VDDQ")
		)
		(pad "G8" smd circle
			(at -2.399995 -1.199998 270)
			(size 0.3556 0.3556)
			(layers "B.Cu" "B.Mask" "B.Paste")
			(net "GND")
		)
		(pad "G9" smd circle
			(at -3.199994 -1.199998 270)
			(size 0.3556 0.3556)
			(layers "B.Cu" "B.Mask" "B.Paste")
			(net "GND")
		)
		(pad "H1" smd circle
			(at 3.199994 -0.399999 270)
			(size 0.3556 0.3556)
			(layers "B.Cu" "B.Mask" "B.Paste")
			(net "DDR0_32A_VREF0B")
		)
		(pad "H2" smd circle
			(at 2.399995 -0.399999 270)
			(size 0.3556 0.3556)
			(layers "B.Cu" "B.Mask" "B.Paste")
			(net "DDR_VDDQ")
		)
		(pad "H3" smd circle
			(at 1.599997 -0.399999 270)
			(size 0.3556 0.3556)
			(layers "B.Cu" "B.Mask" "B.Paste")
			(net "DDR0_32A_DQ4")
		)
		(pad "H7" smd circle
			(at -1.599997 -0.399999 270)
			(size 0.3556 0.3556)
			(layers "B.Cu" "B.Mask" "B.Paste")
			(net "DDR0_32A_DQ3")
		)
		(pad "H8" smd circle
			(at -2.399995 -0.399999 270)
			(size 0.3556 0.3556)
			(layers "B.Cu" "B.Mask" "B.Paste")
			(net "DDR0_32A_DQ2")
		)
		(pad "H9" smd circle
			(at -3.199994 -0.399999 270)
			(size 0.3556 0.3556)
			(layers "B.Cu" "B.Mask" "B.Paste")
			(net "DDR_VDDQ")
		)
		(pad "J1" smd circle
			(at 3.199994 0.399999 270)
			(size 0.3556 0.3556)
			(layers "B.Cu" "B.Mask" "B.Paste")
			(net "Net_91")
		)
		(pad "J2" smd circle
			(at 2.399995 0.399999 270)
			(size 0.3556 0.3556)
			(layers "B.Cu" "B.Mask" "B.Paste")
			(net "GND")
		)
		(pad "J3" smd circle
			(at 1.599997 0.399999 270)
			(size 0.3556 0.3556)
			(layers "B.Cu" "B.Mask" "B.Paste")
			(net "DDR0_32A_RAS_L")
		)
		(pad "J7" smd circle
			(at -1.599997 0.399999 270)
			(size 0.3556 0.3556)
			(layers "B.Cu" "B.Mask" "B.Paste")
			(net "DDR0_32A_CK0_P")
		)
		(pad "J8" smd circle
			(at -2.399995 0.399999 270)
			(size 0.3556 0.3556)
			(layers "B.Cu" "B.Mask" "B.Paste")
			(net "GND")
		)
		(pad "J9" smd circle
			(at -3.199994 0.399999 270)
			(size 0.3556 0.3556)
			(layers "B.Cu" "B.Mask" "B.Paste")
			(net "Net_496")
		)
		(pad "K1" smd circle
			(at 3.199994 1.199998 270)
			(size 0.3556 0.3556)
			(layers "B.Cu" "B.Mask" "B.Paste")
			(net "DDR0_32A_ODT0")
		)
		(pad "K2" smd circle
			(at 2.399995 1.199998 270)
			(size 0.3556 0.3556)
			(layers "B.Cu" "B.Mask" "B.Paste")
			(net "DDR_VDDQ")
		)
		(pad "K3" smd circle
			(at 1.599997 1.199998 270)
			(size 0.3556 0.3556)
			(layers "B.Cu" "B.Mask" "B.Paste")
			(net "DDR0_32A_CAS_L")
		)
		(pad "K7" smd circle
			(at -1.599997 1.199998 270)
			(size 0.3556 0.3556)
			(layers "B.Cu" "B.Mask" "B.Paste")
			(net "DDR0_32A_CK0_N")
		)
		(pad "K8" smd circle
			(at -2.399995 1.199998 270)
			(size 0.3556 0.3556)
			(layers "B.Cu" "B.Mask" "B.Paste")
			(net "DDR_VDDQ")
		)
		(pad "K9" smd circle
			(at -3.199994 1.199998 270)
			(size 0.3556 0.3556)
			(layers "B.Cu" "B.Mask" "B.Paste")
			(net "DDR0_32A_CKE0")
		)
		(pad "L1" smd circle
			(at 3.199994 1.999996 270)
			(size 0.3556 0.3556)
			(layers "B.Cu" "B.Mask" "B.Paste")
			(net "Net_494")
		)
		(pad "L2" smd circle
			(at 2.399995 1.999996 270)
			(size 0.3556 0.3556)
			(layers "B.Cu" "B.Mask" "B.Paste")
			(net "DDR0_32A_CS0_L")
		)
		(pad "L3" smd circle
			(at 1.599997 1.999996 270)
			(size 0.3556 0.3556)
			(layers "B.Cu" "B.Mask" "B.Paste")
			(net "DDR0_32A_WE_L")
		)
		(pad "L7" smd circle
			(at -1.599997 1.999996 270)
			(size 0.3556 0.3556)
			(layers "B.Cu" "B.Mask" "B.Paste")
			(net "DDR0_32A_A10")
		)
		(pad "L8" smd circle
			(at -2.399995 1.999996 270)
			(size 0.3556 0.3556)
			(layers "B.Cu" "B.Mask" "B.Paste")
			(net "12N2312")
		)
		(pad "L9" smd circle
			(at -3.199994 1.999996 270)
			(size 0.3556 0.3556)
			(layers "B.Cu" "B.Mask" "B.Paste")
			(net "Net_497")
		)
		(pad "M1" smd circle
			(at 3.199994 2.799994 270)
			(size 0.3556 0.3556)
			(layers "B.Cu" "B.Mask" "B.Paste")
			(net "GND")
		)
		(pad "M2" smd circle
			(at 2.399995 2.799994 270)
			(size 0.3556 0.3556)
			(layers "B.Cu" "B.Mask" "B.Paste")
			(net "DDR0_32A_BA0")
		)
		(pad "M3" smd circle
			(at 1.599997 2.799994 270)
			(size 0.3556 0.3556)
			(layers "B.Cu" "B.Mask" "B.Paste")
			(net "DDR0_32A_BA2")
		)
		(pad "M7" smd circle
			(at -1.599997 2.799994 270)
			(size 0.3556 0.3556)
			(layers "B.Cu" "B.Mask" "B.Paste")
			(net "Net_495")
		)
		(pad "M8" smd circle
			(at -2.399995 2.799994 270)
			(size 0.3556 0.3556)
			(layers "B.Cu" "B.Mask" "B.Paste")
			(net "DDR0_32A_VREF0B")
		)
		(pad "M9" smd circle
			(at -3.199994 2.799994 270)
			(size 0.3556 0.3556)
			(layers "B.Cu" "B.Mask" "B.Paste")
			(net "GND")
		)
		(pad "N1" smd circle
			(at 3.199994 3.599993 270)
			(size 0.3556 0.3556)
			(layers "B.Cu" "B.Mask" "B.Paste")
			(net "DDR_VDDQ")
		)
		(pad "N2" smd circle
			(at 2.399995 3.599993 270)
			(size 0.3556 0.3556)
			(layers "B.Cu" "B.Mask" "B.Paste")
			(net "DDR0_32A_A3")
		)
		(pad "N3" smd circle
			(at 1.599997 3.599993 270)
			(size 0.3556 0.3556)
			(layers "B.Cu" "B.Mask" "B.Paste")
			(net "DDR0_32A_A0")
		)
		(pad "N7" smd circle
			(at -1.599997 3.599993 270)
			(size 0.3556 0.3556)
			(layers "B.Cu" "B.Mask" "B.Paste")
			(net "DDR0_32A_A12")
		)
		(pad "N8" smd circle
			(at -2.399995 3.599993 270)
			(size 0.3556 0.3556)
			(layers "B.Cu" "B.Mask" "B.Paste")
			(net "DDR0_32A_BA1")
		)
		(pad "N9" smd circle
			(at -3.199994 3.599993 270)
			(size 0.3556 0.3556)
			(layers "B.Cu" "B.Mask" "B.Paste")
			(net "DDR_VDDQ")
		)
		(pad "P1" smd circle
			(at 3.199994 4.399991 270)
			(size 0.3556 0.3556)
			(layers "B.Cu" "B.Mask" "B.Paste")
			(net "GND")
		)
		(pad "P2" smd circle
			(at 2.399995 4.399991 270)
			(size 0.3556 0.3556)
			(layers "B.Cu" "B.Mask" "B.Paste")
			(net "DDR0_32A_A5")
		)
		(pad "P3" smd circle
			(at 1.599997 4.399991 270)
			(size 0.3556 0.3556)
			(layers "B.Cu" "B.Mask" "B.Paste")
			(net "DDR0_32A_A2")
		)
		(pad "P7" smd circle
			(at -1.599997 4.399991 270)
			(size 0.3556 0.3556)
			(layers "B.Cu" "B.Mask" "B.Paste")
			(net "DDR0_32A_A1")
		)
		(pad "P8" smd circle
			(at -2.399995 4.399991 270)
			(size 0.3556 0.3556)
			(layers "B.Cu" "B.Mask" "B.Paste")
			(net "DDR0_32A_A4")
		)
		(pad "P9" smd circle
			(at -3.199994 4.399991 270)
			(size 0.3556 0.3556)
			(layers "B.Cu" "B.Mask" "B.Paste")
			(net "GND")
		)
		(pad "R1" smd circle
			(at 3.199994 5.19999 270)
			(size 0.3556 0.3556)
			(layers "B.Cu" "B.Mask" "B.Paste")
			(net "DDR_VDDQ")
		)
		(pad "R2" smd circle
			(at 2.399995 5.19999 270)
			(size 0.3556 0.3556)
			(layers "B.Cu" "B.Mask" "B.Paste")
			(net "DDR0_32A_A7")
		)
		(pad "R3" smd circle
			(at 1.599997 5.19999 270)
			(size 0.3556 0.3556)
			(layers "B.Cu" "B.Mask" "B.Paste")
			(net "DDR0_32A_A9")
		)
		(pad "R7" smd circle
			(at -1.599997 5.19999 270)
			(size 0.3556 0.3556)
			(layers "B.Cu" "B.Mask" "B.Paste")
			(net "DDR0_32A_A11")
		)
		(pad "R8" smd circle
			(at -2.399995 5.19999 270)
			(size 0.3556 0.3556)
			(layers "B.Cu" "B.Mask" "B.Paste")
			(net "DDR0_32A_A6")
		)
		(pad "R9" smd circle
			(at -3.199994 5.19999 270)
			(size 0.3556 0.3556)
			(layers "B.Cu" "B.Mask" "B.Paste")
			(net "DDR_VDDQ")
		)
		(pad "T1" smd circle
			(at 3.199994 5.999988 270)
			(size 0.3556 0.3556)
			(layers "B.Cu" "B.Mask" "B.Paste")
			(net "GND")
		)
		(pad "T2" smd circle
			(at 2.399995 5.999988 270)
			(size 0.3556 0.3556)
			(layers "B.Cu" "B.Mask" "B.Paste")
			(net "DDR0_32A_DRAMRST_L")
		)
		(pad "T3" smd circle
			(at 1.599997 5.999988 270)
			(size 0.3556 0.3556)
			(layers "B.Cu" "B.Mask" "B.Paste")
			(net "DDR0_32A_A13")
		)
		(pad "T7" smd circle
			(at -1.599997 5.999988 270)
			(size 0.3556 0.3556)
			(layers "B.Cu" "B.Mask" "B.Paste")
			(net "DDR0_32A_A14")
		)
		(pad "T8" smd circle
			(at -2.399995 5.999988 270)
			(size 0.3556 0.3556)
			(layers "B.Cu" "B.Mask" "B.Paste")
			(net "DDR0_32A_A8")
		)
		(pad "T9" smd circle
			(at -3.199994 5.999988 270)
			(size 0.3556 0.3556)
			(layers "B.Cu" "B.Mask" "B.Paste")
			(net "GND")
		)
	)
	(footprint ""
		(layer "B.Cu")
		(at 81.850992 25.013006)
		(property "Reference" "V3_A-A03"
			(at 0 0 0)
			(layer "B.SilkS")
			(hide yes)
			(effects
				(font
					(size 1.27 1.27)
				)
				(justify mirror)
			)
		)
		(property "Value" ""
			(at 0 0 0)
			(layer "B.Fab")
			(effects
				(font
					(size 1.27 1.27)
				)
				(justify mirror)
			)
		)
		(duplicate_pad_numbers_are_jumpers no)
		(pad "1" thru_hole circle
			(at 0 0 180)
			(size 0.4572 0.4572)
			(drill 0.20574)
			(layers "*.Cu" "*.Mask")
			(remove_unused_layers no)
			(net "DDR0_32A_A3")
			(clearance 0.1143)
			(thermal_gap 0.1143)
		)
	)
)
